(kicad_pcb
	(version 20260206)
	(generator "pcbnew")
	(generator_version "10.0")
	(general
		(thickness 1.6)
		(legacy_teardrops no)
	)
	(paper "A4")
	(title_block
		(title "03242023_DA0F0TMBIJ0_F0T_Motherboard_J_brd_V01_OCP.brd")
		(comment 1 "Grand Teton / footprints 5794-5800 of 6105")
	)
	(layers
		(0 "F.Cu" signal "TOP")
		(4 "In1.Cu" signal "GND")
		(6 "In2.Cu" signal "IN1")
		(8 "In3.Cu" signal "GND1")
		(10 "In4.Cu" signal "IN2")
		(12 "In5.Cu" signal "GND2")
		(14 "In6.Cu" signal "IN3")
		(16 "In7.Cu" signal "GND3")
		(18 "In8.Cu" signal "VCC")
		(20 "In9.Cu" signal "VCC1")
		(22 "In10.Cu" signal "GND4")
		(24 "In11.Cu" signal "IN4")
		(26 "In12.Cu" signal "GND5")
		(28 "In13.Cu" signal "IN5")
		(30 "In14.Cu" signal "GND6")
		(32 "In15.Cu" signal "IN6")
		(34 "In16.Cu" signal "GND7")
		(2 "B.Cu" signal "BOTTOM")
		(9 "F.Adhes" user "F.Adhesive")
		(11 "B.Adhes" user "B.Adhesive")
		(13 "F.Paste" user "Package Geometry/Pastemask Top")
		(15 "B.Paste" user "Package Geometry/Pastemask Bottom")
		(5 "F.SilkS" user "Ref Des/Silkscreen Top")
		(7 "B.SilkS" user "Ref Des/Silkscreen Bottom")
		(1 "F.Mask" user "Board Geometry/Soldermask Top")
		(3 "B.Mask" user "Board Geometry/Soldermask Bottom")
		(17 "Dwgs.User" user "User.Drawings")
		(19 "Cmts.User" user "User.Comments")
		(21 "Eco1.User" user "User.Eco1")
		(23 "Eco2.User" user "User.Eco2")
		(25 "Edge.Cuts" user "Board Geometry/Outline")
		(27 "Margin" user)
		(31 "F.CrtYd" user "Package Geometry/Place Bound Top")
		(29 "B.CrtYd" user "Package Geometry/Place Bound Bottom")
		(35 "F.Fab" user "Ref Des/Assembly Top")
		(33 "B.Fab" user "Ref Des/Assembly Bottom")
	)
	(footprint ""
		(layer "B.Cu")
		(at 297.44416 -52.283868)
		(property "Reference" "C1182"
			(at 0 0 0)
			(layer "B.SilkS")
			(hide yes)
			(effects
				(font
					(size 1.27 1.27)
				)
				(justify mirror)
			)
		)
		(property "Value" ""
			(at 0 0 0)
			(layer "B.Fab")
			(effects
				(font
					(size 1.27 1.27)
				)
				(justify mirror)
			)
		)
		(duplicate_pad_numbers_are_jumpers no)
		(fp_line
			(start -1.2954 -0.5842)
			(end -1.2954 0.5842)
			(stroke
				(width 0.1524)
				(type default)
			)
			(layer "B.SilkS")
		)
		(fp_line
			(start -1.2954 0.5842)
			(end 1.2954 0.5842)
			(stroke
				(width 0.1524)
				(type default)
			)
			(layer "B.SilkS")
		)
		(fp_line
			(start 0 -0.5842)
			(end 0 0.5842)
			(stroke
				(width 0.1524)
				(type default)
			)
			(layer "B.SilkS")
		)
		(fp_line
			(start 1.2954 -0.5842)
			(end -1.2954 -0.5842)
			(stroke
				(width 0.1524)
				(type default)
			)
			(layer "B.SilkS")
		)
		(fp_line
			(start 1.2954 0.5842)
			(end 1.2954 -0.5842)
			(stroke
				(width 0.1524)
				(type default)
			)
			(layer "B.SilkS")
		)
		(fp_line
			(start -1.1938 -0.4064)
			(end -1.1938 0.4064)
			(stroke
				(width 0.1)
				(type default)
			)
			(layer "B.Fab")
		)
		(fp_line
			(start -1.1938 0.4064)
			(end -0.8636 0.4064)
			(stroke
				(width 0.1)
				(type default)
			)
			(layer "B.Fab")
		)
		(fp_line
			(start -0.8636 -0.4572)
			(end -0.8636 -0.4064)
			(stroke
				(width 0.1)
				(type default)
			)
			(layer "B.Fab")
		)
		(fp_line
			(start -0.8636 -0.4064)
			(end -1.1938 -0.4064)
			(stroke
				(width 0.1)
				(type default)
			)
			(layer "B.Fab")
		)
		(fp_line
			(start -0.8636 0.4064)
			(end -0.8636 0.4572)
			(stroke
				(width 0.1)
				(type default)
			)
			(layer "B.Fab")
		)
		(fp_line
			(start -0.8636 0.4572)
			(end 0.8636 0.4572)
			(stroke
				(width 0.1)
				(type default)
			)
			(layer "B.Fab")
		)
		(fp_line
			(start 0.8636 -0.4572)
			(end -0.8636 -0.4572)
			(stroke
				(width 0.1)
				(type default)
			)
			(layer "B.Fab")
		)
		(fp_line
			(start 0.8636 -0.4064)
			(end 0.8636 -0.4572)
			(stroke
				(width 0.1)
				(type default)
			)
			(layer "B.Fab")
		)
		(fp_line
			(start 0.8636 0.4064)
			(end 1.1938 0.4064)
			(stroke
				(width 0.1)
				(type default)
			)
			(layer "B.Fab")
		)
		(fp_line
			(start 0.8636 0.4572)
			(end 0.8636 0.4064)
			(stroke
				(width 0.1)
				(type default)
			)
			(layer "B.Fab")
		)
		(fp_line
			(start 1.1938 -0.4064)
			(end 0.8636 -0.4064)
			(stroke
				(width 0.1)
				(type default)
			)
			(layer "B.Fab")
		)
		(fp_line
			(start 1.1938 0.4064)
			(end 1.1938 -0.4064)
			(stroke
				(width 0.1)
				(type default)
			)
			(layer "B.Fab")
		)
		(pad "1" smd rect
			(at 0.7366 0 270)
			(size 0.7112 0.8128)
			(layers "B.Cu" "B.Mask" "B.Paste")
			(net "P1V05_PCH_AUX")
		)
		(pad "2" smd rect
			(at -0.7366 0 270)
			(size 0.7112 0.8128)
			(layers "B.Cu" "B.Mask" "B.Paste")
			(net "GND")
		)
	)
	(footprint ""
		(layer "B.Cu")
		(at 158.84017 -250.58243 90)
		(property "Reference" "C477"
			(at 0 0 90)
			(layer "B.SilkS")
			(hide yes)
			(effects
				(font
					(size 1.27 1.27)
				)
				(justify mirror)
			)
		)
		(property "Value" ""
			(at 0 0 90)
			(layer "B.Fab")
			(effects
				(font
					(size 1.27 1.27)
				)
				(justify mirror)
			)
		)
		(duplicate_pad_numbers_are_jumpers no)
		(fp_line
			(start 1.524 -0.762)
			(end -1.524 -0.762)
			(stroke
				(width 0.1524)
				(type default)
			)
			(layer "B.SilkS")
		)
		(fp_line
			(start -1.524 -0.762)
			(end -1.524 0.762)
			(stroke
				(width 0.1524)
				(type default)
			)
			(layer "B.SilkS")
		)
		(fp_line
			(start 1.524 0.762)
			(end 1.524 -0.762)
			(stroke
				(width 0.1524)
				(type default)
			)
			(layer "B.SilkS")
		)
		(fp_line
			(start -1.524 0.762)
			(end 1.524 0.762)
			(stroke
				(width 0.1524)
				(type default)
			)
			(layer "B.SilkS")
		)
		(fp_line
			(start 1.1049 -0.724916)
			(end 1.1049 0.724916)
			(stroke
				(width 0.1)
				(type default)
			)
			(layer "B.Fab")
		)
		(fp_line
			(start -1.1049 -0.724916)
			(end 1.1049 -0.724916)
			(stroke
				(width 0.1)
				(type default)
			)
			(layer "B.Fab")
		)
		(fp_line
			(start 1.1049 0.724916)
			(end -1.1049 0.724916)
			(stroke
				(width 0.1)
				(type default)
			)
			(layer "B.Fab")
		)
		(fp_line
			(start -1.1049 0.724916)
			(end -1.1049 -0.724916)
			(stroke
				(width 0.1)
				(type default)
			)
			(layer "B.Fab")
		)
		(pad "1" smd rect
			(at 0.889 0 90)
			(size 1.016 1.27)
			(layers "B.Cu" "B.Mask" "B.Paste")
			(net "PVCCFA_EHV_FIVRA_CPU1")
		)
		(pad "2" smd rect
			(at -0.889 0 90)
			(size 1.016 1.27)
			(layers "B.Cu" "B.Mask" "B.Paste")
			(net "GND")
		)
	)
	(footprint ""
		(layer "B.Cu")
		(at 370.695474 -354.93833 90)
		(property "Reference" "R2332"
			(at 0 0 90)
			(layer "B.SilkS")
			(hide yes)
			(effects
				(font
					(size 1.27 1.27)
				)
				(justify mirror)
			)
		)
		(property "Value" ""
			(at 0 0 90)
			(layer "B.Fab")
			(effects
				(font
					(size 1.27 1.27)
				)
				(justify mirror)
			)
		)
		(duplicate_pad_numbers_are_jumpers no)
		(fp_line
			(start 0.7874 -0.4064)
			(end -0.7874 -0.4064)
			(stroke
				(width 0.1524)
				(type default)
			)
			(layer "B.SilkS")
		)
		(fp_line
			(start -0.7874 -0.4064)
			(end -0.7874 0.4064)
			(stroke
				(width 0.1524)
				(type default)
			)
			(layer "B.SilkS")
		)
		(fp_line
			(start 0.7874 0.4064)
			(end 0.7874 -0.4064)
			(stroke
				(width 0.1524)
				(type default)
			)
			(layer "B.SilkS")
		)
		(fp_line
			(start -0.7874 0.4064)
			(end 0.7874 0.4064)
			(stroke
				(width 0.1524)
				(type default)
			)
			(layer "B.SilkS")
		)
		(fp_line
			(start 0.67945 -0.305054)
			(end 0.12065 -0.305054)
			(stroke
				(width 0.1)
				(type default)
			)
			(layer "B.Fab")
		)
		(fp_line
			(start 0.12065 -0.305054)
			(end 0.12065 -0.2794)
			(stroke
				(width 0.1)
				(type default)
			)
			(layer "B.Fab")
		)
		(fp_line
			(start -0.12065 -0.3048)
			(end -0.67945 -0.3048)
			(stroke
				(width 0.1)
				(type default)
			)
			(layer "B.Fab")
		)
		(fp_line
			(start -0.67945 -0.3048)
			(end -0.67945 0.3048)
			(stroke
				(width 0.1)
				(type default)
			)
			(layer "B.Fab")
		)
		(fp_line
			(start 0.12065 -0.2794)
			(end -0.12065 -0.2794)
			(stroke
				(width 0.1)
				(type default)
			)
			(layer "B.Fab")
		)
		(fp_line
			(start -0.12065 -0.2794)
			(end -0.12065 -0.3048)
			(stroke
				(width 0.1)
				(type default)
			)
			(layer "B.Fab")
		)
		(fp_line
			(start 0.12065 0.2794)
			(end 0.12065 0.3048)
			(stroke
				(width 0.1)
				(type default)
			)
			(layer "B.Fab")
		)
		(fp_line
			(start -0.120396 0.2794)
			(end 0.12065 0.2794)
			(stroke
				(width 0.1)
				(type default)
			)
			(layer "B.Fab")
		)
		(fp_line
			(start 0.67945 0.3048)
			(end 0.67945 -0.305054)
			(stroke
				(width 0.1)
				(type default)
			)
			(layer "B.Fab")
		)
		(fp_line
			(start 0.12065 0.3048)
			(end 0.67945 0.3048)
			(stroke
				(width 0.1)
				(type default)
			)
			(layer "B.Fab")
		)
		(fp_line
			(start -0.120396 0.3048)
			(end -0.120396 0.2794)
			(stroke
				(width 0.1)
				(type default)
			)
			(layer "B.Fab")
		)
		(fp_line
			(start -0.67945 0.3048)
			(end -0.120396 0.3048)
			(stroke
				(width 0.1)
				(type default)
			)
			(layer "B.Fab")
		)
		(pad "1" smd circle
			(at 0.40005 0 270)
			(size 0 0)
			(layers "B.Cu" "B.Mask" "B.Paste")
			(net "FM_PVPP_HBM_CPU0_EN")
		)
		(pad "2" smd circle
			(at -0.40005 0 270)
			(size 0 0)
			(layers "B.Cu" "B.Mask" "B.Paste")
			(net "GND")
		)
	)
	(footprint ""
		(layer "B.Cu")
		(at 289.907726 -362.795058 90)
		(property "Reference" "PC1180_P0_4"
			(at 0 0 90)
			(layer "B.SilkS")
			(hide yes)
			(effects
				(font
					(size 1.27 1.27)
				)
				(justify mirror)
			)
		)
		(property "Value" ""
			(at 0 0 90)
			(layer "B.Fab")
			(effects
				(font
					(size 1.27 1.27)
				)
				(justify mirror)
			)
		)
		(duplicate_pad_numbers_are_jumpers no)
		(fp_line
			(start 1.524 -0.762)
			(end -1.524 -0.762)
			(stroke
				(width 0.1524)
				(type default)
			)
			(layer "B.SilkS")
		)
		(fp_line
			(start -1.524 -0.762)
			(end -1.524 0.762)
			(stroke
				(width 0.1524)
				(type default)
			)
			(layer "B.SilkS")
		)
		(fp_line
			(start 1.524 0.762)
			(end 1.524 -0.762)
			(stroke
				(width 0.1524)
				(type default)
			)
			(layer "B.SilkS")
		)
		(fp_line
			(start -1.524 0.762)
			(end 1.524 0.762)
			(stroke
				(width 0.1524)
				(type default)
			)
			(layer "B.SilkS")
		)
		(fp_line
			(start 1.1049 -0.724916)
			(end 1.1049 0.724916)
			(stroke
				(width 0.1)
				(type default)
			)
			(layer "B.Fab")
		)
		(fp_line
			(start -1.1049 -0.724916)
			(end 1.1049 -0.724916)
			(stroke
				(width 0.1)
				(type default)
			)
			(layer "B.Fab")
		)
		(fp_line
			(start 1.1049 0.724916)
			(end -1.1049 0.724916)
			(stroke
				(width 0.1)
				(type default)
			)
			(layer "B.Fab")
		)
		(fp_line
			(start -1.1049 0.724916)
			(end -1.1049 -0.724916)
			(stroke
				(width 0.1)
				(type default)
			)
			(layer "B.Fab")
		)
		(pad "1" smd rect
			(at 0.889 0 90)
			(size 1.016 1.27)
			(layers "B.Cu" "B.Mask" "B.Paste")
			(net "SW_P12V_PVCCFA_EHV_FIVRA_CPU0_L")
		)
		(pad "2" smd rect
			(at -0.889 0 90)
			(size 1.016 1.27)
			(layers "B.Cu" "B.Mask" "B.Paste")
			(net "GND")
		)
	)
	(footprint ""
		(layer "B.Cu")
		(at 16.207994 -99.842066)
		(property "Reference" "C2038"
			(at 0 0 0)
			(layer "B.SilkS")
			(hide yes)
			(effects
				(font
					(size 1.27 1.27)
				)
				(justify mirror)
			)
		)
		(property "Value" ""
			(at 0 0 0)
			(layer "B.Fab")
			(effects
				(font
					(size 1.27 1.27)
				)
				(justify mirror)
			)
		)
		(duplicate_pad_numbers_are_jumpers no)
		(fp_line
			(start -0.7874 -0.4064)
			(end -0.7874 0.4064)
			(stroke
				(width 0.1524)
				(type default)
			)
			(layer "B.SilkS")
		)
		(fp_line
			(start -0.7874 0.4064)
			(end 0.7874 0.4064)
			(stroke
				(width 0.1524)
				(type default)
			)
			(layer "B.SilkS")
		)
		(fp_line
			(start 0.7874 -0.4064)
			(end -0.7874 -0.4064)
			(stroke
				(width 0.1524)
				(type default)
			)
			(layer "B.SilkS")
		)
		(fp_line
			(start 0.7874 0.4064)
			(end 0.7874 -0.4064)
			(stroke
				(width 0.1524)
				(type default)
			)
			(layer "B.SilkS")
		)
		(fp_line
			(start -0.67945 -0.3048)
			(end -0.67945 0.3048)
			(stroke
				(width 0.1)
				(type default)
			)
			(layer "B.Fab")
		)
		(fp_line
			(start -0.67945 0.3048)
			(end -0.120396 0.3048)
			(stroke
				(width 0.1)
				(type default)
			)
			(layer "B.Fab")
		)
		(fp_line
			(start -0.12065 -0.3048)
			(end -0.67945 -0.3048)
			(stroke
				(width 0.1)
				(type default)
			)
			(layer "B.Fab")
		)
		(fp_line
			(start -0.12065 -0.2794)
			(end -0.12065 -0.3048)
			(stroke
				(width 0.1)
				(type default)
			)
			(layer "B.Fab")
		)
		(fp_line
			(start -0.120396 0.2794)
			(end 0.12065 0.2794)
			(stroke
				(width 0.1)
				(type default)
			)
			(layer "B.Fab")
		)
		(fp_line
			(start -0.120396 0.3048)
			(end -0.120396 0.2794)
			(stroke
				(width 0.1)
				(type default)
			)
			(layer "B.Fab")
		)
		(fp_line
			(start 0.12065 -0.305054)
			(end 0.12065 -0.2794)
			(stroke
				(width 0.1)
				(type default)
			)
			(layer "B.Fab")
		)
		(fp_line
			(start 0.12065 -0.2794)
			(end -0.12065 -0.2794)
			(stroke
				(width 0.1)
				(type default)
			)
			(layer "B.Fab")
		)
		(fp_line
			(start 0.12065 0.2794)
			(end 0.12065 0.3048)
			(stroke
				(width 0.1)
				(type default)
			)
			(layer "B.Fab")
		)
		(fp_line
			(start 0.12065 0.3048)
			(end 0.67945 0.3048)
			(stroke
				(width 0.1)
				(type default)
			)
			(layer "B.Fab")
		)
		(fp_line
			(start 0.67945 -0.305054)
			(end 0.12065 -0.305054)
			(stroke
				(width 0.1)
				(type default)
			)
			(layer "B.Fab")
		)
		(fp_line
			(start 0.67945 0.3048)
			(end 0.67945 -0.305054)
			(stroke
				(width 0.1)
				(type default)
			)
			(layer "B.Fab")
		)
		(pad "1" smd circle
			(at 0.40005 0 180)
			(size 0 0)
			(layers "B.Cu" "B.Mask" "B.Paste")
			(net "P3V3_AUX_USB_HUB")
		)
		(pad "2" smd circle
			(at -0.40005 0 180)
			(size 0 0)
			(layers "B.Cu" "B.Mask" "B.Paste")
			(net "GND")
		)
	)
	(footprint ""
		(layer "B.Cu")
		(at 52.375054 -353.567492 90)
		(property "Reference" "PC404_P1_2"
			(at 0 0 90)
			(layer "B.SilkS")
			(hide yes)
			(effects
				(font
					(size 1.27 1.27)
				)
				(justify mirror)
			)
		)
		(property "Value" ""
			(at 0 0 90)
			(layer "B.Fab")
			(effects
				(font
					(size 1.27 1.27)
				)
				(justify mirror)
			)
		)
		(duplicate_pad_numbers_are_jumpers no)
		(fp_line
			(start 1.524 -0.762)
			(end -1.524 -0.762)
			(stroke
				(width 0.1524)
				(type default)
			)
			(layer "B.SilkS")
		)
		(fp_line
			(start -1.524 -0.762)
			(end -1.524 0.762)
			(stroke
				(width 0.1524)
				(type default)
			)
			(layer "B.SilkS")
		)
		(fp_line
			(start 1.524 0.762)
			(end 1.524 -0.762)
			(stroke
				(width 0.1524)
				(type default)
			)
			(layer "B.SilkS")
		)
		(fp_line
			(start -1.524 0.762)
			(end 1.524 0.762)
			(stroke
				(width 0.1524)
				(type default)
			)
			(layer "B.SilkS")
		)
		(fp_line
			(start 1.1049 -0.724916)
			(end 1.1049 0.724916)
			(stroke
				(width 0.1)
				(type default)
			)
			(layer "B.Fab")
		)
		(fp_line
			(start -1.1049 -0.724916)
			(end 1.1049 -0.724916)
			(stroke
				(width 0.1)
				(type default)
			)
			(layer "B.Fab")
		)
		(fp_line
			(start 1.1049 0.724916)
			(end -1.1049 0.724916)
			(stroke
				(width 0.1)
				(type default)
			)
			(layer "B.Fab")
		)
		(fp_line
			(start -1.1049 0.724916)
			(end -1.1049 -0.724916)
			(stroke
				(width 0.1)
				(type default)
			)
			(layer "B.Fab")
		)
		(pad "1" smd rect
			(at 0.889 0 90)
			(size 1.016 1.27)
			(layers "B.Cu" "B.Mask" "B.Paste")
			(net "SW_P12V_PVCCFA_EHV_FIVRA_CPU1_L")
		)
		(pad "2" smd rect
			(at -0.889 0 90)
			(size 1.016 1.27)
			(layers "B.Cu" "B.Mask" "B.Paste")
			(net "GND")
		)
	)
	(footprint ""
		(layer "B.Cu")
		(at 301.731172 -362.795058 90)
		(property "Reference" "PC611_P0_2"
			(at 0 0 90)
			(layer "B.SilkS")
			(hide yes)
			(effects
				(font
					(size 1.27 1.27)
				)
				(justify mirror)
			)
		)
		(property "Value" ""
			(at 0 0 90)
			(layer "B.Fab")
			(effects
				(font
					(size 1.27 1.27)
				)
				(justify mirror)
			)
		)
		(duplicate_pad_numbers_are_jumpers no)
		(fp_line
			(start 1.524 -0.762)
			(end -1.524 -0.762)
			(stroke
				(width 0.1524)
				(type default)
			)
			(layer "B.SilkS")
		)
		(fp_line
			(start -1.524 -0.762)
			(end -1.524 0.762)
			(stroke
				(width 0.1524)
				(type default)
			)
			(layer "B.SilkS")
		)
		(fp_line
			(start 1.524 0.762)
			(end 1.524 -0.762)
			(stroke
				(width 0.1524)
				(type default)
			)
			(layer "B.SilkS")
		)
		(fp_line
			(start -1.524 0.762)
			(end 1.524 0.762)
			(stroke
				(width 0.1524)
				(type default)
			)
			(layer "B.SilkS")
		)
		(fp_line
			(start 1.1049 -0.724916)
			(end 1.1049 0.724916)
			(stroke
				(width 0.1)
				(type default)
			)
			(layer "B.Fab")
		)
		(fp_line
			(start -1.1049 -0.724916)
			(end 1.1049 -0.724916)
			(stroke
				(width 0.1)
				(type default)
			)
			(layer "B.Fab")
		)
		(fp_line
			(start 1.1049 0.724916)
			(end -1.1049 0.724916)
			(stroke
				(width 0.1)
				(type default)
			)
			(layer "B.Fab")
		)
		(fp_line
			(start -1.1049 0.724916)
			(end -1.1049 -0.724916)
			(stroke
				(width 0.1)
				(type default)
			)
			(layer "B.Fab")
		)
		(pad "1" smd rect
			(at 0.889 0 90)
			(size 1.016 1.27)
			(layers "B.Cu" "B.Mask" "B.Paste")
			(net "SW_P12V_PVCCFA_EHV_FIVRA_CPU0_L")
		)
		(pad "2" smd rect
			(at -0.889 0 90)
			(size 1.016 1.27)
			(layers "B.Cu" "B.Mask" "B.Paste")
			(net "GND")
		)
	)
)
